# S9S_MB_2U (Grand Teton) — schematic netlist excerpt (pin names and nets, part order shuffled) for the footprints in the layout excerpt that follows; sources: Cadence DE-HDL packaged netlist, KiCad conversion of 03242023_DA0F0TMBIJ0_F0T_Motherboard_J_brd_V01_OCP.brd

Q100  MOSFET_NCH_DUAL  NX6008NBKS IC  pkg SOT363XB  page 256
  S1  = GND
  G1  = RST_PLD_CPU1_DRAM_EF_N
  D2  = LED_RST_PLD_CPU1_DRAM_GH_N_D
  S2  = GND
  G2  = RST_PLD_CPU1_DRAM_GH_N
  D1  = LED_RST_PLD_CPU1_DRAM_EF_N_D

C273  Q_CAP  22UF 4V 20% X6S  pkg C0402  page 77 : A = PVCCIN_CPU1 ; B = GND

(kicad_pcb
	(version 20260206)
	(generator "pcbnew")
	(generator_version "10.0")
	(general
		(thickness 1.6)
		(legacy_teardrops no)
	)
	(paper "A4")
	(title_block
		(title "03242023_DA0F0TMBIJ0_F0T_Motherboard_J_brd_V01_OCP.brd")
		(comment 1 "Grand Teton / footprints 3391-3392 of 6105")
	)
	(layers
		(0 "F.Cu" signal "TOP")
		(4 "In1.Cu" signal "GND")
		(6 "In2.Cu" signal "IN1")
		(8 "In3.Cu" signal "GND1")
		(10 "In4.Cu" signal "IN2")
		(12 "In5.Cu" signal "GND2")
		(14 "In6.Cu" signal "IN3")
		(16 "In7.Cu" signal "GND3")
		(18 "In8.Cu" signal "VCC")
		(20 "In9.Cu" signal "VCC1")
		(22 "In10.Cu" signal "GND4")
		(24 "In11.Cu" signal "IN4")
		(26 "In12.Cu" signal "GND5")
		(28 "In13.Cu" signal "IN5")
		(30 "In14.Cu" signal "GND6")
		(32 "In15.Cu" signal "IN6")
		(34 "In16.Cu" signal "GND7")
		(2 "B.Cu" signal "BOTTOM")
		(9 "F.Adhes" user "F.Adhesive")
		(11 "B.Adhes" user "B.Adhesive")
		(13 "F.Paste" user "Package Geometry/Pastemask Top")
		(15 "B.Paste" user "Package Geometry/Pastemask Bottom")
		(5 "F.SilkS" user "Ref Des/Silkscreen Top")
		(7 "B.SilkS" user "Ref Des/Silkscreen Bottom")
		(1 "F.Mask" user "Board Geometry/Soldermask Top")
		(3 "B.Mask" user "Board Geometry/Soldermask Bottom")
		(17 "Dwgs.User" user "User.Drawings")
		(19 "Cmts.User" user "User.Comments")
		(21 "Eco1.User" user "User.Eco1")
		(23 "Eco2.User" user "User.Eco2")
		(25 "Edge.Cuts" user "Board Geometry/Outline")
		(27 "Margin" user)
		(31 "F.CrtYd" user "Package Geometry/Place Bound Top")
		(29 "B.CrtYd" user "Package Geometry/Place Bound Bottom")
		(35 "F.Fab" user "Ref Des/Assembly Top")
		(33 "B.Fab" user "Ref Des/Assembly Bottom")
	)
	(footprint ""
		(layer "F.Cu")
		(at 117.526816 -247.715278 90)
		(property "Reference" "C273"
			(at 0 0 90)
			(layer "F.SilkS")
			(hide yes)
			(effects
				(font
					(size 1.27 1.27)
				)
			)
		)
		(property "Value" ""
			(at 0 0 90)
			(layer "F.Fab")
			(effects
				(font
					(size 1.27 1.27)
				)
			)
		)
		(duplicate_pad_numbers_are_jumpers no)
		(fp_line
			(start 0.7874 -0.4064)
			(end 0.7874 0.4064)
			(stroke
				(width 0.1524)
				(type default)
			)
			(layer "F.SilkS")
		)
		(fp_line
			(start -0.7874 -0.4064)
			(end 0.7874 -0.4064)
			(stroke
				(width 0.1524)
				(type default)
			)
			(layer "F.SilkS")
		)
		(fp_line
			(start 0.7874 0.4064)
			(end -0.7874 0.4064)
			(stroke
				(width 0.1524)
				(type default)
			)
			(layer "F.SilkS")
		)
		(fp_line
			(start -0.7874 0.4064)
			(end -0.7874 -0.4064)
			(stroke
				(width 0.1524)
				(type default)
			)
			(layer "F.SilkS")
		)
		(fp_line
			(start -0.12065 -0.305054)
			(end -0.12065 -0.2794)
			(stroke
				(width 0.1)
				(type default)
			)
			(layer "F.Fab")
		)
		(fp_line
			(start -0.67945 -0.305054)
			(end -0.12065 -0.305054)
			(stroke
				(width 0.1)
				(type default)
			)
			(layer "F.Fab")
		)
		(fp_line
			(start 0.67945 -0.3048)
			(end 0.67945 0.3048)
			(stroke
				(width 0.1)
				(type default)
			)
			(layer "F.Fab")
		)
		(fp_line
			(start 0.12065 -0.3048)
			(end 0.67945 -0.3048)
			(stroke
				(width 0.1)
				(type default)
			)
			(layer "F.Fab")
		)
		(fp_line
			(start 0.12065 -0.2794)
			(end 0.12065 -0.3048)
			(stroke
				(width 0.1)
				(type default)
			)
			(layer "F.Fab")
		)
		(fp_line
			(start -0.12065 -0.2794)
			(end 0.12065 -0.2794)
			(stroke
				(width 0.1)
				(type default)
			)
			(layer "F.Fab")
		)
		(fp_line
			(start 0.120396 0.2794)
			(end -0.12065 0.2794)
			(stroke
				(width 0.1)
				(type default)
			)
			(layer "F.Fab")
		)
		(fp_line
			(start -0.12065 0.2794)
			(end -0.12065 0.3048)
			(stroke
				(width 0.1)
				(type default)
			)
			(layer "F.Fab")
		)
		(fp_line
			(start 0.67945 0.3048)
			(end 0.120396 0.3048)
			(stroke
				(width 0.1)
				(type default)
			)
			(layer "F.Fab")
		)
		(fp_line
			(start 0.120396 0.3048)
			(end 0.120396 0.2794)
			(stroke
				(width 0.1)
				(type default)
			)
			(layer "F.Fab")
		)
		(fp_line
			(start -0.12065 0.3048)
			(end -0.67945 0.3048)
			(stroke
				(width 0.1)
				(type default)
			)
			(layer "F.Fab")
		)
		(fp_line
			(start -0.67945 0.3048)
			(end -0.67945 -0.305054)
			(stroke
				(width 0.1)
				(type default)
			)
			(layer "F.Fab")
		)
		(pad "1" smd circle
			(at -0.40005 0 90)
			(size 0 0)
			(layers "F.Cu" "F.Mask" "F.Paste")
			(net "PVCCIN_CPU1")
		)
		(pad "2" smd circle
			(at 0.40005 0 90)
			(size 0 0)
			(layers "F.Cu" "F.Mask" "F.Paste")
			(net "GND")
		)
	)
	(footprint ""
		(layer "F.Cu")
		(at 85.626194 -102.509574 180)
		(property "Reference" "Q100"
			(at 3.226308 0.425196 0)
			(unlocked yes)
			(layer "F.SilkS")
			(effects
				(font
					(size 0.7874 0.5842)
					(thickness 0.1524)
				)
			)
		)
		(property "Value" ""
			(at 0 0 180)
			(layer "F.Fab")
			(effects
				(font
					(size 1.27 1.27)
				)
			)
		)
		(duplicate_pad_numbers_are_jumpers no)
		(fp_line
			(start 1.376172 1.199896)
			(end -1.376172 1.199896)
			(stroke
				(width 0.1524)
				(type default)
			)
			(layer "F.SilkS")
		)
		(fp_line
			(start 1.376172 -1.199896)
			(end 1.376172 1.199896)
			(stroke
				(width 0.1524)
				(type default)
			)
			(layer "F.SilkS")
		)
		(fp_line
			(start 0.508 -1.199896)
			(end 1.376172 -1.199896)
			(stroke
				(width 0.1524)
				(type default)
			)
			(layer "F.SilkS")
		)
		(fp_line
			(start 0 -0.762)
			(end 0.508 -1.199896)
			(stroke
				(width 0.1524)
				(type default)
			)
			(layer "F.SilkS")
		)
		(fp_line
			(start -0.508 -1.199896)
			(end 0 -0.762)
			(stroke
				(width 0.1524)
				(type default)
			)
			(layer "F.SilkS")
		)
		(fp_line
			(start -1.376172 1.199896)
			(end -1.376172 -1.199896)
			(stroke
				(width 0.1524)
				(type default)
			)
			(layer "F.SilkS")
		)
		(fp_line
			(start -1.376172 -1.199896)
			(end -0.508 -1.199896)
			(stroke
				(width 0.1524)
				(type default)
			)
			(layer "F.SilkS")
		)
		(fp_poly
			(pts
				(xy -2.04724 -0.7747) (xy -2.80924 -0.3937) (xy -2.80924 -1.1557)
			)
			(stroke
				(width 0)
				(type default)
			)
			(fill yes)
			(layer "F.SilkS")
		)
		(fp_line
			(start 0.674878 1.100074)
			(end -0.674878 1.100074)
			(stroke
				(width 0.1)
				(type default)
			)
			(layer "F.Fab")
		)
		(fp_line
			(start 0.674878 -1.100074)
			(end 0.674878 1.100074)
			(stroke
				(width 0.1)
				(type default)
			)
			(layer "F.Fab")
		)
		(fp_line
			(start -0.674878 1.100074)
			(end -0.674878 -1.100074)
			(stroke
				(width 0.1)
				(type default)
			)
			(layer "F.Fab")
		)
		(fp_line
			(start -0.674878 -1.100074)
			(end 0.674878 -1.100074)
			(stroke
				(width 0.1)
				(type default)
			)
			(layer "F.Fab")
		)
		(fp_poly
			(pts
				(xy -1.4605 -0.7493) (xy -2.2225 -1.1303) (xy -2.2225 -0.3683)
			)
			(stroke
				(width 0)
				(type default)
			)
			(fill yes)
			(layer "F.Fab")
		)
		(pad "1" smd rect
			(at -0.899922 -0.750062 90)
			(size 0.6096 0.6096)
			(layers "F.Cu" "F.Mask" "F.Paste")
			(net "GND")
		)
		(pad "2" smd rect
			(at -0.899922 0 90)
			(size 0.4064 0.6096)
			(layers "F.Cu" "F.Mask" "F.Paste")
			(net "RST_PLD_CPU1_DRAM_EF_N")
		)
		(pad "3" smd rect
			(at -0.899922 0.750062 90)
			(size 0.6096 0.6096)
			(layers "F.Cu" "F.Mask" "F.Paste")
			(net "LED_RST_PLD_CPU1_DRAM_GH_N_D")
		)
		(pad "4" smd rect
			(at 0.899922 0.750062 90)
			(size 0.6096 0.6096)
			(layers "F.Cu" "F.Mask" "F.Paste")
			(net "GND")
		)
		(pad "5" smd rect
			(at 0.899922 0 90)
			(size 0.4064 0.6096)
			(layers "F.Cu" "F.Mask" "F.Paste")
			(net "RST_PLD_CPU1_DRAM_GH_N")
		)
		(pad "6" smd rect
			(at 0.899922 -0.750062 90)
			(size 0.6096 0.6096)
			(layers "F.Cu" "F.Mask" "F.Paste")
			(net "LED_RST_PLD_CPU1_DRAM_EF_N_D")
		)
	)
)
